(kicad_pcb
	(version 20260206)
	(generator "pcbnew")
	(generator_version "10.0")
	(general
		(thickness 1.6)
		(legacy_teardrops no)
	)
	(paper "A4")
	(title_block
		(title "Bryce Canyon_SCC_16316-1_OCP.brd")
		(comment 1 "Bryce Canyon / footprints 1027-1033 of 1561")
	)
	(layers
		(0 "F.Cu" signal "TOP")
		(4 "In1.Cu" signal "L2GND")
		(6 "In2.Cu" signal "L3")
		(8 "In3.Cu" signal "L4VCC")
		(10 "In4.Cu" signal "L5VCC")
		(12 "In5.Cu" signal "L6")
		(14 "In6.Cu" signal "L7GND")
		(2 "B.Cu" signal "BOTTOM")
		(9 "F.Adhes" user "F.Adhesive")
		(11 "B.Adhes" user "B.Adhesive")
		(13 "F.Paste" user "Package Geometry/Pastemask Top")
		(15 "B.Paste" user "Package Geometry/Pastemask Bottom")
		(5 "F.SilkS" user "Ref Des/Silkscreen Top")
		(7 "B.SilkS" user "Ref Des/Silkscreen Bottom")
		(1 "F.Mask" user "Board Geometry/Soldermask Top")
		(3 "B.Mask" user "Board Geometry/Soldermask Bottom")
		(17 "Dwgs.User" user "User.Drawings")
		(19 "Cmts.User" user "User.Comments")
		(21 "Eco1.User" user "User.Eco1")
		(23 "Eco2.User" user "User.Eco2")
		(25 "Edge.Cuts" user "Board Geometry/Outline")
		(27 "Margin" user)
		(31 "F.CrtYd" user "Package Geometry/Place Bound Top")
		(29 "B.CrtYd" user "Package Geometry/Place Bound Bottom")
		(35 "F.Fab" user "Ref Des/Assembly Top")
		(33 "B.Fab" user "Ref Des/Assembly Bottom")
	)
	(footprint ""
		(layer "B.Cu")
		(at 116.501418 -80.51927 180)
		(property "Reference" "C149"
			(at 0 0 0)
			(layer "B.SilkS")
			(hide yes)
			(effects
				(font
					(size 1.27 1.27)
				)
				(justify mirror)
			)
		)
		(property "Value" "SCD1U6D3V1KX-GP"
			(at 2.8321 -1.7399 180)
			(unlocked yes)
			(layer "B.Fab")
			(hide yes)
			(effects
				(font
					(size 1.016 1.016)
					(thickness 0.1524)
				)
				(justify mirror)
			)
		)
		(property "Device Type" "C0201H13"
			(at 2.8321 -3.2639 180)
			(unlocked yes)
			(layer "B.Fab")
			(hide yes)
			(effects
				(font
					(size 1.016 1.016)
					(thickness 0.1524)
				)
				(justify mirror)
			)
		)
		(duplicate_pad_numbers_are_jumpers no)
		(fp_rect
			(start 0.2794 0.6477)
			(end -0.2794 -0.6477)
			(stroke
				(width 0)
				(type default)
			)
			(fill no)
			(layer "B.CrtYd")
		)
		(fp_rect
			(start 0.2794 0.6477)
			(end -0.2794 -0.6477)
			(stroke
				(width 0)
				(type default)
			)
			(fill no)
			(layer "B.Fab")
		)
		(pad "1" smd custom
			(at 0 -0.2794)
			(size 0.0762 0.0762)
			(layers "B.Cu" "B.Mask" "B.Paste")
			(net "P1V8_E")
			(options
				(clearance outline)
				(anchor circle)
			)
			(primitives
				(gr_poly
					(pts
						(arc
							(start 0.1524 0.127)
							(mid 0.137521 0.162921)
							(end 0.1016 0.1778)
						)
						(arc
							(start -0.1016 0.1778)
							(mid -0.137521 0.162921)
							(end -0.1524 0.127)
						)
						(arc
							(start -0.1524 -0.127)
							(mid -0.137521 -0.162921)
							(end -0.1016 -0.1778)
						)
						(arc
							(start 0.1016 -0.1778)
							(mid 0.137521 -0.162921)
							(end 0.1524 -0.127)
						)
					)
					(width 0)
					(fill yes)
				)
			)
		)
		(pad "2" smd custom
			(at 0 0.2794)
			(size 0.0762 0.0762)
			(layers "B.Cu" "B.Mask" "B.Paste")
			(net "GND")
			(options
				(clearance outline)
				(anchor circle)
			)
			(primitives
				(gr_poly
					(pts
						(arc
							(start 0.1524 0.127)
							(mid 0.137521 0.162921)
							(end 0.1016 0.1778)
						)
						(arc
							(start -0.1016 0.1778)
							(mid -0.137521 0.162921)
							(end -0.1524 0.127)
						)
						(arc
							(start -0.1524 -0.127)
							(mid -0.137521 -0.162921)
							(end -0.1016 -0.1778)
						)
						(arc
							(start 0.1016 -0.1778)
							(mid 0.137521 -0.162921)
							(end 0.1524 -0.127)
						)
					)
					(width 0)
					(fill yes)
				)
			)
		)
	)
	(footprint ""
		(layer "B.Cu")
		(at 168.2496 -32.6771 -90)
		(property "Reference" "C381"
			(at 0 0 90)
			(layer "B.SilkS")
			(hide yes)
			(effects
				(font
					(size 1.27 1.27)
				)
				(justify mirror)
			)
		)
		(property "Value" "SCD1U16V2KX-3GP"
			(at -1.1811 -2.7051 270)
			(unlocked yes)
			(layer "B.Fab")
			(hide yes)
			(effects
				(font
					(size 1.016 1.016)
					(thickness 0.1524)
				)
				(justify mirror)
			)
		)
		(property "Device Type" "C402H22"
			(at -1.1811 -4.2291 270)
			(unlocked yes)
			(layer "B.Fab")
			(hide yes)
			(effects
				(font
					(size 1.016 1.016)
					(thickness 0.1524)
				)
				(justify mirror)
			)
		)
		(duplicate_pad_numbers_are_jumpers no)
		(fp_rect
			(start 0.4318 0.9525)
			(end -0.4318 -0.9525)
			(stroke
				(width 0)
				(type default)
			)
			(fill no)
			(layer "B.CrtYd")
		)
		(fp_rect
			(start 0.4318 0.9525)
			(end -0.4318 -0.9525)
			(stroke
				(width 0)
				(type default)
			)
			(fill no)
			(layer "B.Fab")
		)
		(pad "1" smd custom
			(at 0 -0.4445 90)
			(size 0.1524 0.1524)
			(layers "B.Cu" "B.Mask" "B.Paste")
			(net "PCE_VDDH")
			(options
				(clearance outline)
				(anchor circle)
			)
			(primitives
				(gr_poly
					(pts
						(arc
							(start 0.3048 0.2032)
							(mid 0.275042 0.275042)
							(end 0.2032 0.3048)
						)
						(arc
							(start -0.2032 0.3048)
							(mid -0.275042 0.275042)
							(end -0.3048 0.2032)
						)
						(arc
							(start -0.3048 -0.2032)
							(mid -0.275042 -0.275042)
							(end -0.2032 -0.3048)
						)
						(arc
							(start 0.2032 -0.3048)
							(mid 0.275042 -0.275042)
							(end 0.3048 -0.2032)
						)
					)
					(width 0)
					(fill yes)
				)
			)
		)
		(pad "2" smd custom
			(at 0 0.4445 90)
			(size 0.1524 0.1524)
			(layers "B.Cu" "B.Mask" "B.Paste")
			(net "GND")
			(options
				(clearance outline)
				(anchor circle)
			)
			(primitives
				(gr_poly
					(pts
						(arc
							(start 0.3048 0.2032)
							(mid 0.275042 0.275042)
							(end 0.2032 0.3048)
						)
						(arc
							(start -0.2032 0.3048)
							(mid -0.275042 0.275042)
							(end -0.3048 0.2032)
						)
						(arc
							(start -0.3048 -0.2032)
							(mid -0.275042 -0.275042)
							(end -0.2032 -0.3048)
						)
						(arc
							(start 0.2032 -0.3048)
							(mid 0.275042 -0.275042)
							(end 0.3048 -0.2032)
						)
					)
					(width 0)
					(fill yes)
				)
			)
		)
	)
	(footprint ""
		(layer "B.Cu")
		(at 122.4788 -62.484 -90)
		(property "Reference" "C301"
			(at 0 0 90)
			(layer "B.SilkS")
			(hide yes)
			(effects
				(font
					(size 1.27 1.27)
				)
				(justify mirror)
			)
		)
		(property "Value" "SCD1U6D3V1KX-GP"
			(at 2.8321 -1.7399 270)
			(unlocked yes)
			(layer "B.Fab")
			(hide yes)
			(effects
				(font
					(size 1.016 1.016)
					(thickness 0.1524)
				)
				(justify mirror)
			)
		)
		(property "Device Type" "C0201H13"
			(at 2.8321 -3.2639 270)
			(unlocked yes)
			(layer "B.Fab")
			(hide yes)
			(effects
				(font
					(size 1.016 1.016)
					(thickness 0.1524)
				)
				(justify mirror)
			)
		)
		(duplicate_pad_numbers_are_jumpers no)
		(fp_rect
			(start 0.2794 0.6477)
			(end -0.2794 -0.6477)
			(stroke
				(width 0)
				(type default)
			)
			(fill no)
			(layer "B.CrtYd")
		)
		(fp_rect
			(start 0.2794 0.6477)
			(end -0.2794 -0.6477)
			(stroke
				(width 0)
				(type default)
			)
			(fill no)
			(layer "B.Fab")
		)
		(pad "1" smd custom
			(at 0 -0.2794 90)
			(size 0.0762 0.0762)
			(layers "B.Cu" "B.Mask" "B.Paste")
			(net "GB_VDDA")
			(options
				(clearance outline)
				(anchor circle)
			)
			(primitives
				(gr_poly
					(pts
						(arc
							(start 0.1524 0.127)
							(mid 0.137521 0.162921)
							(end 0.1016 0.1778)
						)
						(arc
							(start -0.1016 0.1778)
							(mid -0.137521 0.162921)
							(end -0.1524 0.127)
						)
						(arc
							(start -0.1524 -0.127)
							(mid -0.137521 -0.162921)
							(end -0.1016 -0.1778)
						)
						(arc
							(start 0.1016 -0.1778)
							(mid 0.137521 -0.162921)
							(end 0.1524 -0.127)
						)
					)
					(width 0)
					(fill yes)
				)
			)
		)
		(pad "2" smd custom
			(at 0 0.2794 90)
			(size 0.0762 0.0762)
			(layers "B.Cu" "B.Mask" "B.Paste")
			(net "GND")
			(options
				(clearance outline)
				(anchor circle)
			)
			(primitives
				(gr_poly
					(pts
						(arc
							(start 0.1524 0.127)
							(mid 0.137521 0.162921)
							(end 0.1016 0.1778)
						)
						(arc
							(start -0.1016 0.1778)
							(mid -0.137521 0.162921)
							(end -0.1524 0.127)
						)
						(arc
							(start -0.1524 -0.127)
							(mid -0.137521 -0.162921)
							(end -0.1016 -0.1778)
						)
						(arc
							(start 0.1016 -0.1778)
							(mid 0.137521 -0.162921)
							(end 0.1524 -0.127)
						)
					)
					(width 0)
					(fill yes)
				)
			)
		)
	)
	(footprint ""
		(layer "B.Cu")
		(at 76.454 -41.148 180)
		(property "Reference" "C310"
			(at 0 0 0)
			(layer "B.SilkS")
			(hide yes)
			(effects
				(font
					(size 1.27 1.27)
				)
				(justify mirror)
			)
		)
		(property "Value" "SC22U6D3V3MX-9-GP-U"
			(at 0 -2.8194 180)
			(unlocked yes)
			(layer "B.Fab")
			(hide yes)
			(effects
				(font
					(size 1.016 1.016)
					(thickness 0.1524)
				)
				(justify mirror)
			)
		)
		(property "Device Type" "C603H40"
			(at 0 -4.3434 180)
			(unlocked yes)
			(layer "B.Fab")
			(hide yes)
			(effects
				(font
					(size 1.016 1.016)
					(thickness 0.1524)
				)
				(justify mirror)
			)
		)
		(duplicate_pad_numbers_are_jumpers no)
		(fp_line
			(start -0.508 0)
			(end 0.508 0)
			(stroke
				(width 0.2032)
				(type default)
			)
			(layer "B.SilkS")
		)
		(fp_rect
			(start 0.5842 1.3335)
			(end -0.5842 -1.3335)
			(stroke
				(width 0)
				(type default)
			)
			(fill no)
			(layer "B.CrtYd")
		)
		(fp_rect
			(start 0.5842 1.3335)
			(end -0.5842 -1.3335)
			(stroke
				(width 0)
				(type default)
			)
			(fill no)
			(layer "B.Fab")
		)
		(pad "1" smd custom
			(at 0 -0.762)
			(size 0.2159 0.2159)
			(layers "B.Cu" "B.Mask" "B.Paste")
			(net "GB_VDDA")
			(options
				(clearance outline)
				(anchor circle)
			)
			(primitives
				(gr_poly
					(pts
						(arc
							(start -0.3302 0.4318)
							(mid -0.402042 0.402042)
							(end -0.4318 0.3302)
						)
						(arc
							(start -0.4318 -0.3302)
							(mid -0.402042 -0.402042)
							(end -0.3302 -0.4318)
						)
						(arc
							(start 0.3302 -0.4318)
							(mid 0.402042 -0.402042)
							(end 0.4318 -0.3302)
						)
						(arc
							(start 0.4318 0.3302)
							(mid 0.402042 0.402042)
							(end 0.3302 0.4318)
						)
					)
					(width 0)
					(fill yes)
				)
			)
		)
		(pad "2" smd custom
			(at 0 0.762)
			(size 0.2159 0.2159)
			(layers "B.Cu" "B.Mask" "B.Paste")
			(net "GND")
			(options
				(clearance outline)
				(anchor circle)
			)
			(primitives
				(gr_poly
					(pts
						(arc
							(start -0.3302 0.4318)
							(mid -0.402042 0.402042)
							(end -0.4318 0.3302)
						)
						(arc
							(start -0.4318 -0.3302)
							(mid -0.402042 -0.402042)
							(end -0.3302 -0.4318)
						)
						(arc
							(start 0.3302 -0.4318)
							(mid 0.402042 -0.402042)
							(end 0.4318 -0.3302)
						)
						(arc
							(start 0.4318 0.3302)
							(mid 0.402042 0.402042)
							(end 0.3302 0.4318)
						)
					)
					(width 0)
					(fill yes)
				)
			)
		)
	)
	(footprint ""
		(layer "B.Cu")
		(at 130.429 -78.74 -90)
		(property "Reference" "C137"
			(at 0 0 90)
			(layer "B.SilkS")
			(hide yes)
			(effects
				(font
					(size 1.27 1.27)
				)
				(justify mirror)
			)
		)
		(property "Value" "SCD1U6D3V1KX-GP"
			(at 2.8321 -1.7399 270)
			(unlocked yes)
			(layer "B.Fab")
			(hide yes)
			(effects
				(font
					(size 1.016 1.016)
					(thickness 0.1524)
				)
				(justify mirror)
			)
		)
		(property "Device Type" "C0201H13"
			(at 2.8321 -3.2639 270)
			(unlocked yes)
			(layer "B.Fab")
			(hide yes)
			(effects
				(font
					(size 1.016 1.016)
					(thickness 0.1524)
				)
				(justify mirror)
			)
		)
		(duplicate_pad_numbers_are_jumpers no)
		(fp_rect
			(start 0.2794 0.6477)
			(end -0.2794 -0.6477)
			(stroke
				(width 0)
				(type default)
			)
			(fill no)
			(layer "B.CrtYd")
		)
		(fp_rect
			(start 0.2794 0.6477)
			(end -0.2794 -0.6477)
			(stroke
				(width 0)
				(type default)
			)
			(fill no)
			(layer "B.Fab")
		)
		(pad "1" smd custom
			(at 0 -0.2794 90)
			(size 0.0762 0.0762)
			(layers "B.Cu" "B.Mask" "B.Paste")
			(net "P1V8_E")
			(options
				(clearance outline)
				(anchor circle)
			)
			(primitives
				(gr_poly
					(pts
						(arc
							(start 0.1524 0.127)
							(mid 0.137521 0.162921)
							(end 0.1016 0.1778)
						)
						(arc
							(start -0.1016 0.1778)
							(mid -0.137521 0.162921)
							(end -0.1524 0.127)
						)
						(arc
							(start -0.1524 -0.127)
							(mid -0.137521 -0.162921)
							(end -0.1016 -0.1778)
						)
						(arc
							(start 0.1016 -0.1778)
							(mid 0.137521 -0.162921)
							(end 0.1524 -0.127)
						)
					)
					(width 0)
					(fill yes)
				)
			)
		)
		(pad "2" smd custom
			(at 0 0.2794 90)
			(size 0.0762 0.0762)
			(layers "B.Cu" "B.Mask" "B.Paste")
			(net "GND")
			(options
				(clearance outline)
				(anchor circle)
			)
			(primitives
				(gr_poly
					(pts
						(arc
							(start 0.1524 0.127)
							(mid 0.137521 0.162921)
							(end 0.1016 0.1778)
						)
						(arc
							(start -0.1016 0.1778)
							(mid -0.137521 0.162921)
							(end -0.1524 0.127)
						)
						(arc
							(start -0.1524 -0.127)
							(mid -0.137521 -0.162921)
							(end -0.1016 -0.1778)
						)
						(arc
							(start 0.1016 -0.1778)
							(mid 0.137521 -0.162921)
							(end 0.1524 -0.127)
						)
					)
					(width 0)
					(fill yes)
				)
			)
		)
	)
	(footprint ""
		(layer "B.Cu")
		(at 129.417318 -87.260684)
		(property "Reference" "R212"
			(at 0 0 0)
			(layer "B.SilkS")
			(hide yes)
			(effects
				(font
					(size 1.27 1.27)
				)
				(justify mirror)
			)
		)
		(property "Value" "4K75R2F-1-GP"
			(at -0.064008 -3.993896 0)
			(unlocked yes)
			(layer "B.Fab")
			(hide yes)
			(effects
				(font
					(size 1.016 1.016)
					(thickness 0.1524)
				)
				(justify mirror)
			)
		)
		(property "Device Type" "R402H16"
			(at -0.064008 -5.517896 0)
			(unlocked yes)
			(layer "B.Fab")
			(hide yes)
			(effects
				(font
					(size 1.016 1.016)
					(thickness 0.1524)
				)
				(justify mirror)
			)
		)
		(duplicate_pad_numbers_are_jumpers no)
		(fp_line
			(start -0.508 -0.9398)
			(end 0.508 -0.9398)
			(stroke
				(width 0.1524)
				(type default)
			)
			(layer "B.SilkS")
		)
		(fp_line
			(start 0.508 -0.9398)
			(end 0.508 0.9398)
			(stroke
				(width 0.1524)
				(type default)
			)
			(layer "B.SilkS")
		)
		(fp_rect
			(start 0.508 0.9398)
			(end -0.508 -0.9398)
			(stroke
				(width 0)
				(type default)
			)
			(fill no)
			(layer "B.CrtYd")
		)
		(fp_rect
			(start 0.508 0.9398)
			(end -0.508 -0.9398)
			(stroke
				(width 0)
				(type default)
			)
			(fill no)
			(layer "B.Fab")
		)
		(pad "1" smd custom
			(at 0 -0.4445 180)
			(size 0.1397 0.1397)
			(layers "B.Cu" "B.Mask" "B.Paste")
			(net "P1V8_E")
			(options
				(clearance outline)
				(anchor circle)
			)
			(primitives
				(gr_poly
					(pts
						(arc
							(start -0.1778 0.2794)
							(mid -0.249642 0.249642)
							(end -0.2794 0.1778)
						)
						(arc
							(start -0.2794 -0.1778)
							(mid -0.249642 -0.249642)
							(end -0.1778 -0.2794)
						)
						(arc
							(start 0.1778 -0.2794)
							(mid 0.249642 -0.249642)
							(end 0.2794 -0.1778)
						)
						(arc
							(start 0.2794 0.1778)
							(mid 0.249642 0.249642)
							(end 0.1778 0.2794)
						)
					)
					(width 0)
					(fill yes)
				)
			)
		)
		(pad "2" smd custom
			(at 0 0.4445 180)
			(size 0.1397 0.1397)
			(layers "B.Cu" "B.Mask" "B.Paste")
			(net "ICE_TMS")
			(options
				(clearance outline)
				(anchor circle)
			)
			(primitives
				(gr_poly
					(pts
						(arc
							(start -0.1778 0.2794)
							(mid -0.249642 0.249642)
							(end -0.2794 0.1778)
						)
						(arc
							(start -0.2794 -0.1778)
							(mid -0.249642 -0.249642)
							(end -0.1778 -0.2794)
						)
						(arc
							(start 0.1778 -0.2794)
							(mid 0.249642 -0.249642)
							(end 0.2794 -0.1778)
						)
						(arc
							(start 0.2794 0.1778)
							(mid 0.249642 0.249642)
							(end 0.1778 0.2794)
						)
					)
					(width 0)
					(fill yes)
				)
			)
		)
	)
	(footprint ""
		(layer "B.Cu")
		(at 180.848 -31.75 -90)
		(property "Reference" "C469"
			(at 0 0 90)
			(layer "B.SilkS")
			(hide yes)
			(effects
				(font
					(size 1.27 1.27)
				)
				(justify mirror)
			)
		)
		(property "Value" "SCD1U6D3V1KX-GP"
			(at 2.8321 -1.7399 270)
			(unlocked yes)
			(layer "B.Fab")
			(hide yes)
			(effects
				(font
					(size 1.016 1.016)
					(thickness 0.1524)
				)
				(justify mirror)
			)
		)
		(property "Device Type" "C0201H13"
			(at 2.8321 -3.2639 270)
			(unlocked yes)
			(layer "B.Fab")
			(hide yes)
			(effects
				(font
					(size 1.016 1.016)
					(thickness 0.1524)
				)
				(justify mirror)
			)
		)
		(duplicate_pad_numbers_are_jumpers no)
		(fp_rect
			(start 0.2794 0.6477)
			(end -0.2794 -0.6477)
			(stroke
				(width 0)
				(type default)
			)
			(fill no)
			(layer "B.CrtYd")
		)
		(fp_rect
			(start 0.2794 0.6477)
			(end -0.2794 -0.6477)
			(stroke
				(width 0)
				(type default)
			)
			(fill no)
			(layer "B.Fab")
		)
		(pad "1" smd custom
			(at 0 -0.2794 90)
			(size 0.0762 0.0762)
			(layers "B.Cu" "B.Mask" "B.Paste")
			(net "P1V8_C")
			(options
				(clearance outline)
				(anchor circle)
			)
			(primitives
				(gr_poly
					(pts
						(arc
							(start 0.1524 0.127)
							(mid 0.137521 0.162921)
							(end 0.1016 0.1778)
						)
						(arc
							(start -0.1016 0.1778)
							(mid -0.137521 0.162921)
							(end -0.1524 0.127)
						)
						(arc
							(start -0.1524 -0.127)
							(mid -0.137521 -0.162921)
							(end -0.1016 -0.1778)
						)
						(arc
							(start 0.1016 -0.1778)
							(mid 0.137521 -0.162921)
							(end 0.1524 -0.127)
						)
					)
					(width 0)
					(fill yes)
				)
			)
		)
		(pad "2" smd custom
			(at 0 0.2794 90)
			(size 0.0762 0.0762)
			(layers "B.Cu" "B.Mask" "B.Paste")
			(net "GND")
			(options
				(clearance outline)
				(anchor circle)
			)
			(primitives
				(gr_poly
					(pts
						(arc
							(start 0.1524 0.127)
							(mid 0.137521 0.162921)
							(end 0.1016 0.1778)
						)
						(arc
							(start -0.1016 0.1778)
							(mid -0.137521 0.162921)
							(end -0.1524 0.127)
						)
						(arc
							(start -0.1524 -0.127)
							(mid -0.137521 -0.162921)
							(end -0.1016 -0.1778)
						)
						(arc
							(start 0.1016 -0.1778)
							(mid 0.137521 -0.162921)
							(end 0.1524 -0.127)
						)
					)
					(width 0)
					(fill yes)
				)
			)
		)
	)
)
